(kicad_pcb
	(version 20260206)
	(generator "pcbnew")
	(generator_version "10.0")
	(general
		(thickness 1.6)
		(legacy_teardrops no)
	)
	(paper "A4")
	(title_block
		(title "Wiwynn_Tioga_Pass_MB.brd")
		(comment 1 "Tioga Pass / footprints 1064-1071 of 4770")
	)
	(layers
		(0 "F.Cu" signal "TOP")
		(4 "In1.Cu" signal "L2GND")
		(6 "In2.Cu" signal "L3")
		(8 "In3.Cu" signal "L4GND")
		(10 "In4.Cu" signal "L5")
		(12 "In5.Cu" signal "L6GND")
		(14 "In6.Cu" signal "L7VCC")
		(16 "In7.Cu" signal "L8VCC")
		(18 "In8.Cu" signal "L9GND")
		(20 "In9.Cu" signal "L10")
		(22 "In10.Cu" signal "L11GND")
		(24 "In11.Cu" signal "L12")
		(26 "In12.Cu" signal "L13GND")
		(2 "B.Cu" signal "BOTTOM")
		(9 "F.Adhes" user "F.Adhesive")
		(11 "B.Adhes" user "B.Adhesive")
		(13 "F.Paste" user "Package Geometry/Pastemask Top")
		(15 "B.Paste" user "Package Geometry/Pastemask Bottom")
		(5 "F.SilkS" user "Ref Des/Silkscreen Top")
		(7 "B.SilkS" user "Ref Des/Silkscreen Bottom")
		(1 "F.Mask" user "Board Geometry/Soldermask Top")
		(3 "B.Mask" user "Board Geometry/Soldermask Bottom")
		(17 "Dwgs.User" user "User.Drawings")
		(19 "Cmts.User" user "User.Comments")
		(21 "Eco1.User" user "User.Eco1")
		(23 "Eco2.User" user "User.Eco2")
		(25 "Edge.Cuts" user "Board Geometry/Outline")
		(27 "Margin" user)
		(31 "F.CrtYd" user "Package Geometry/Place Bound Top")
		(29 "B.CrtYd" user "Package Geometry/Place Bound Bottom")
		(35 "F.Fab" user "Ref Des/Assembly Top")
		(33 "B.Fab" user "Ref Des/Assembly Bottom")
	)
	(footprint ""
		(layer "F.Cu")
		(at 15.494 -80.4545)
		(property "Reference" "R1D24"
			(at 0 0 0)
			(layer "F.SilkS")
			(hide yes)
			(effects
				(font
					(size 1.27 1.27)
				)
			)
		)
		(property "Value" ""
			(at 0 0 0)
			(layer "F.Fab")
			(effects
				(font
					(size 1.27 1.27)
				)
			)
		)
		(duplicate_pad_numbers_are_jumpers no)
		(fp_rect
			(start 0.2794 0.9906)
			(end -0.2794 -0.1016)
			(stroke
				(width 0)
				(type default)
			)
			(fill no)
			(layer "F.CrtYd")
		)
		(fp_line
			(start -0.2794 -0.1016)
			(end -0.2794 0.9906)
			(stroke
				(width 0.1)
				(type default)
			)
			(layer "F.Fab")
		)
		(fp_line
			(start -0.2794 0.9906)
			(end 0.2794 0.9906)
			(stroke
				(width 0.1)
				(type default)
			)
			(layer "F.Fab")
		)
		(fp_line
			(start 0.2794 -0.1016)
			(end -0.2794 -0.1016)
			(stroke
				(width 0.1)
				(type default)
			)
			(layer "F.Fab")
		)
		(fp_line
			(start 0.2794 0.9906)
			(end 0.2794 -0.1016)
			(stroke
				(width 0.1)
				(type default)
			)
			(layer "F.Fab")
		)
		(pad "1" smd rect
			(at 0 0)
			(size 0.508 0.508)
			(layers "F.Cu" "F.Mask" "F.Paste")
			(net "SMB_BMC_PMBUS_STBY_LVC3_SCL")
		)
		(pad "2" smd rect
			(at 0 0.889)
			(size 0.508 0.508)
			(layers "F.Cu" "F.Mask" "F.Paste")
			(net "SMB_3V3SB_HSC_SCL_R")
		)
		(zone
			(layer "F.Cu")
			(hatch none 0.5)
			(connect_pads
				(clearance 0)
			)
			(min_thickness 0.25)
			(keepout
				(tracks allowed)
				(vias not_allowed)
				(pads allowed)
				(copperpour not_allowed)
				(footprints allowed)
			)
			(placement
				(enabled no)
				(sheetname "")
			)
			(fill
				(thermal_gap 0.5)
				(thermal_bridge_width 0.5)
				(island_removal_mode 0)
			)
			(polygon
				(pts
					(xy 15.748 -79.8195) (xy 15.748 -80.2005) (xy 15.24 -80.2005) (xy 15.24 -79.8195)
				)
			)
		)
		(zone
			(layer "F.Cu")
			(hatch none 0.5)
			(connect_pads
				(clearance 0)
			)
			(min_thickness 0.25)
			(keepout
				(tracks not_allowed)
				(vias allowed)
				(pads allowed)
				(copperpour not_allowed)
				(footprints allowed)
			)
			(placement
				(enabled no)
				(sheetname "")
			)
			(fill
				(thermal_gap 0.5)
				(thermal_bridge_width 0.5)
				(island_removal_mode 0)
			)
			(polygon
				(pts
					(xy 15.748 -79.8195) (xy 15.748 -80.2005) (xy 15.24 -80.2005) (xy 15.24 -79.8195)
				)
			)
		)
	)
	(footprint ""
		(layer "F.Cu")
		(at 108.16844 -73.318116)
		(property "Reference" "C3D17"
			(at 0 0 0)
			(layer "F.SilkS")
			(hide yes)
			(effects
				(font
					(size 1.27 1.27)
				)
			)
		)
		(property "Value" ""
			(at 0 0 0)
			(layer "F.Fab")
			(effects
				(font
					(size 1.27 1.27)
				)
			)
		)
		(duplicate_pad_numbers_are_jumpers no)
		(fp_poly
			(pts
				(xy -0.4953 -0.2032) (xy 0.4953 -0.2032) (xy 0.4953 1.6002) (xy -0.4953 1.6002)
			)
			(stroke
				(width 0)
				(type default)
			)
			(fill no)
			(layer "F.CrtYd")
		)
		(fp_line
			(start -0.4953 -0.2032)
			(end 0.4953 -0.2032)
			(stroke
				(width 0.1)
				(type default)
			)
			(layer "F.Fab")
		)
		(fp_line
			(start -0.4953 1.6002)
			(end -0.4953 -0.2032)
			(stroke
				(width 0.1)
				(type default)
			)
			(layer "F.Fab")
		)
		(fp_line
			(start 0.4953 -0.2032)
			(end 0.4953 1.6002)
			(stroke
				(width 0.1)
				(type default)
			)
			(layer "F.Fab")
		)
		(fp_line
			(start 0.4953 1.6002)
			(end -0.4953 1.6002)
			(stroke
				(width 0.1)
				(type default)
			)
			(layer "F.Fab")
		)
		(pad "1" smd rect
			(at 0 0)
			(size 0.762 0.889)
			(layers "F.Cu" "F.Mask" "F.Paste")
			(net "PVCCMCP_CPU1")
		)
		(pad "2" smd rect
			(at 0 1.397)
			(size 0.762 0.889)
			(layers "F.Cu" "F.Mask" "F.Paste")
			(net "GND")
		)
		(zone
			(layer "F.Cu")
			(hatch none 0.5)
			(connect_pads
				(clearance 0)
			)
			(min_thickness 0.25)
			(keepout
				(tracks not_allowed)
				(vias allowed)
				(pads allowed)
				(copperpour not_allowed)
				(footprints allowed)
			)
			(placement
				(enabled no)
				(sheetname "")
			)
			(fill
				(thermal_gap 0.5)
				(thermal_bridge_width 0.5)
				(island_removal_mode 0)
			)
			(polygon
				(pts
					(xy 107.78744 -72.873616) (xy 108.54944 -72.873616) (xy 108.54944 -72.365616) (xy 107.78744 -72.365616)
				)
			)
		)
	)
	(footprint ""
		(layer "F.Cu")
		(at 378.587 -158.1404 -90)
		(property "Reference" "RT44"
			(at 1.01473 0.656336 180)
			(unlocked yes)
			(layer "F.SilkS")
			(effects
				(font
					(size 0.4064 0.254)
					(thickness 0.1524)
				)
			)
		)
		(property "Value" ""
			(at 0 0 270)
			(layer "F.Fab")
			(effects
				(font
					(size 1.27 1.27)
				)
			)
		)
		(duplicate_pad_numbers_are_jumpers no)
		(fp_poly
			(pts
				(xy -0.4953 -0.2032) (xy 0.4953 -0.2032) (xy 0.4953 1.6002) (xy -0.4953 1.6002)
			)
			(stroke
				(width 0)
				(type default)
			)
			(fill no)
			(layer "F.CrtYd")
		)
		(fp_line
			(start -0.4953 1.6002)
			(end -0.4953 -0.2032)
			(stroke
				(width 0.1)
				(type default)
			)
			(layer "F.Fab")
		)
		(fp_line
			(start 0.4953 1.6002)
			(end -0.4953 1.6002)
			(stroke
				(width 0.1)
				(type default)
			)
			(layer "F.Fab")
		)
		(fp_line
			(start -0.4953 -0.2032)
			(end 0.4953 -0.2032)
			(stroke
				(width 0.1)
				(type default)
			)
			(layer "F.Fab")
		)
		(fp_line
			(start 0.4953 -0.2032)
			(end 0.4953 1.6002)
			(stroke
				(width 0.1)
				(type default)
			)
			(layer "F.Fab")
		)
		(pad "1" smd rect
			(at 0 0 270)
			(size 0.762 0.889)
			(layers "F.Cu" "F.Mask" "F.Paste")
			(net "VR_PVNN_PCH_PH1_BOOT")
		)
		(pad "2" smd rect
			(at 0 1.397 270)
			(size 0.762 0.889)
			(layers "F.Cu" "F.Mask" "F.Paste")
			(net "VR_PVNN_PCH_PH1_BOOT_R")
		)
		(zone
			(layer "F.Cu")
			(hatch none 0.5)
			(connect_pads
				(clearance 0)
			)
			(min_thickness 0.25)
			(keepout
				(tracks not_allowed)
				(vias allowed)
				(pads allowed)
				(copperpour not_allowed)
				(footprints allowed)
			)
			(placement
				(enabled no)
				(sheetname "")
			)
			(fill
				(thermal_gap 0.5)
				(thermal_bridge_width 0.5)
				(island_removal_mode 0)
			)
			(polygon
				(pts
					(xy 377.6345 -158.5214) (xy 377.6345 -157.7594) (xy 378.1425 -157.7594) (xy 378.1425 -158.5214)
				)
			)
		)
		(zone
			(layer "F.Cu")
			(hatch none 0.5)
			(connect_pads
				(clearance 0)
			)
			(min_thickness 0.25)
			(keepout
				(tracks allowed)
				(vias not_allowed)
				(pads allowed)
				(copperpour not_allowed)
				(footprints allowed)
			)
			(placement
				(enabled no)
				(sheetname "")
			)
			(fill
				(thermal_gap 0.5)
				(thermal_bridge_width 0.5)
				(island_removal_mode 0)
			)
			(polygon
				(pts
					(xy 377.6345 -157.7594) (xy 378.1425 -157.7594) (xy 378.1425 -158.5214) (xy 377.6345 -158.5214)
				)
			)
		)
	)
	(footprint ""
		(layer "F.Cu")
		(at 29.337 10.7315 -90)
		(property "Reference" "T1P29"
			(at 0 0 270)
			(layer "F.SilkS")
			(hide yes)
			(effects
				(font
					(size 1.27 1.27)
				)
			)
		)
		(property "Value" "*"
			(at 0 -3.44805 270)
			(unlocked yes)
			(layer "F.Fab")
			(hide yes)
			(effects
				(font
					(size 0.889 0.889)
					(thickness 0.1524)
				)
			)
		)
		(property "Device Type" "TPAD-SE-2P-GP_DISCRET-GA1-TPADA"
			(at 0 -4.97205 270)
			(unlocked yes)
			(layer "F.Fab")
			(hide yes)
			(effects
				(font
					(size 0.889 0.889)
					(thickness 0.1524)
				)
			)
		)
		(duplicate_pad_numbers_are_jumpers no)
		(fp_line
			(start -1.016 2.286)
			(end -1.016 -2.286)
			(stroke
				(width 0.1524)
				(type default)
			)
			(layer "F.SilkS")
		)
		(fp_line
			(start 1.016 2.286)
			(end -1.016 2.286)
			(stroke
				(width 0.1524)
				(type default)
			)
			(layer "F.SilkS")
		)
		(fp_line
			(start -1.016 -2.286)
			(end 1.016 -2.286)
			(stroke
				(width 0.1524)
				(type default)
			)
			(layer "F.SilkS")
		)
		(fp_line
			(start 1.016 -2.286)
			(end 1.016 2.286)
			(stroke
				(width 0.1524)
				(type default)
			)
			(layer "F.SilkS")
		)
		(fp_rect
			(start -1.27 2.54)
			(end 1.27 -2.54)
			(stroke
				(width 0)
				(type default)
			)
			(fill no)
			(layer "F.CrtYd")
		)
		(fp_rect
			(start -1.27 2.54)
			(end 1.27 -2.54)
			(stroke
				(width 0)
				(type default)
			)
			(fill no)
			(layer "F.Fab")
		)
		(pad "1" thru_hole circle
			(at 0 -1.27 270)
			(size 1.524 1.524)
			(drill 0.9144)
			(layers "*.Cu" "*.Mask")
			(remove_unused_layers no)
			(net "L12_40OHM_6INCH")
			(clearance -0.0508)
			(thermal_gap 0.127)
			(padstack
				(mode front_inner_back)
				(layer "Inner"
					(shape circle)
					(size 1.1684 1.1684)
					(clearance 0.127)
				)
				(layer "B.Cu"
					(shape circle)
					(size 1.524 1.524)
					(clearance -0.0508)
				)
			)
		)
		(pad "GND1" thru_hole rect
			(at 0 1.27 270)
			(size 1.524 1.524)
			(drill 0.9144)
			(layers "*.Cu" "*.Mask")
			(remove_unused_layers no)
			(net "GND")
			(clearance -0.0508)
			(thermal_gap 0.127)
			(padstack
				(mode front_inner_back)
				(layer "Inner"
					(shape circle)
					(size 1.1684 1.1684)
					(clearance 0.127)
				)
				(layer "B.Cu"
					(shape rect)
					(size 1.524 1.524)
					(clearance -0.0508)
				)
			)
		)
	)
	(footprint ""
		(layer "F.Cu")
		(at 111.633 -69.85)
		(property "Reference" "R3D24"
			(at 0 0 0)
			(layer "F.SilkS")
			(hide yes)
			(effects
				(font
					(size 1.27 1.27)
				)
			)
		)
		(property "Value" ""
			(at 0 0 0)
			(layer "F.Fab")
			(effects
				(font
					(size 1.27 1.27)
				)
			)
		)
		(duplicate_pad_numbers_are_jumpers no)
		(fp_poly
			(pts
				(xy -0.2794 -0.1016) (xy 0.2794 -0.1016) (xy 0.2794 0.9906) (xy -0.2794 0.9906)
			)
			(stroke
				(width 0)
				(type default)
			)
			(fill no)
			(layer "F.CrtYd")
		)
		(fp_line
			(start -0.2794 -0.1016)
			(end -0.2794 0.9906)
			(stroke
				(width 0.1)
				(type default)
			)
			(layer "F.Fab")
		)
		(fp_line
			(start -0.2794 0.9906)
			(end 0.2794 0.9906)
			(stroke
				(width 0.1)
				(type default)
			)
			(layer "F.Fab")
		)
		(fp_line
			(start 0.2794 -0.1016)
			(end -0.2794 -0.1016)
			(stroke
				(width 0.1)
				(type default)
			)
			(layer "F.Fab")
		)
		(fp_line
			(start 0.2794 0.9906)
			(end 0.2794 -0.1016)
			(stroke
				(width 0.1)
				(type default)
			)
			(layer "F.Fab")
		)
		(pad "1" smd rect
			(at 0 0)
			(size 0.508 0.508)
			(layers "F.Cu" "F.Mask" "F.Paste")
			(net "PVCCIO_CPU1")
		)
		(pad "2" smd rect
			(at 0 0.889)
			(size 0.508 0.508)
			(layers "F.Cu" "F.Mask" "F.Paste")
			(net "PU_CPU1_SOCKET_ID_0")
		)
		(zone
			(layer "F.Cu")
			(hatch none 0.5)
			(connect_pads
				(clearance 0)
			)
			(min_thickness 0.25)
			(keepout
				(tracks allowed)
				(vias not_allowed)
				(pads allowed)
				(copperpour not_allowed)
				(footprints allowed)
			)
			(placement
				(enabled no)
				(sheetname "")
			)
			(fill
				(thermal_gap 0.5)
				(thermal_bridge_width 0.5)
				(island_removal_mode 0)
			)
			(polygon
				(pts
					(xy 111.379 -69.596) (xy 111.887 -69.596) (xy 111.887 -69.215) (xy 111.379 -69.215)
				)
			)
		)
		(zone
			(layer "F.Cu")
			(hatch none 0.5)
			(connect_pads
				(clearance 0)
			)
			(min_thickness 0.25)
			(keepout
				(tracks not_allowed)
				(vias allowed)
				(pads allowed)
				(copperpour not_allowed)
				(footprints allowed)
			)
			(placement
				(enabled no)
				(sheetname "")
			)
			(fill
				(thermal_gap 0.5)
				(thermal_bridge_width 0.5)
				(island_removal_mode 0)
			)
			(polygon
				(pts
					(xy 111.379 -69.215) (xy 111.887 -69.215) (xy 111.887 -69.596) (xy 111.379 -69.596)
				)
			)
		)
	)
	(footprint ""
		(layer "F.Cu")
		(at 193.127122 -149.778212 -90)
		(property "Reference" "C4A4"
			(at 0 0 270)
			(layer "F.SilkS")
			(hide yes)
			(effects
				(font
					(size 1.27 1.27)
				)
			)
		)
		(property "Value" ""
			(at 0 0 270)
			(layer "F.Fab")
			(effects
				(font
					(size 1.27 1.27)
				)
			)
		)
		(duplicate_pad_numbers_are_jumpers no)
		(fp_rect
			(start -0.7239 1.9939)
			(end 0.7239 -0.2159)
			(stroke
				(width 0)
				(type default)
			)
			(fill no)
			(layer "F.CrtYd")
		)
		(fp_line
			(start -0.7239 1.9939)
			(end 0.7239 1.9939)
			(stroke
				(width 0.1)
				(type default)
			)
			(layer "F.Fab")
		)
		(fp_line
			(start 0.7239 1.9939)
			(end 0.7239 -0.2159)
			(stroke
				(width 0.1)
				(type default)
			)
			(layer "F.Fab")
		)
		(fp_line
			(start -0.7239 -0.2159)
			(end -0.7239 1.9939)
			(stroke
				(width 0.1)
				(type default)
			)
			(layer "F.Fab")
		)
		(fp_line
			(start 0.7239 -0.2159)
			(end -0.7239 -0.2159)
			(stroke
				(width 0.1)
				(type default)
			)
			(layer "F.Fab")
		)
		(pad "1" smd rect
			(at 0 0 270)
			(size 1.27 1.016)
			(layers "F.Cu" "F.Mask" "F.Paste")
			(net "P12V_NVDIMM_DEF")
		)
		(pad "2" smd rect
			(at 0 1.778 270)
			(size 1.27 1.016)
			(layers "F.Cu" "F.Mask" "F.Paste")
			(net "GND")
		)
		(zone
			(layer "F.Cu")
			(hatch none 0.5)
			(connect_pads
				(clearance 0)
			)
			(min_thickness 0.25)
			(keepout
				(tracks not_allowed)
				(vias allowed)
				(pads allowed)
				(copperpour not_allowed)
				(footprints allowed)
			)
			(placement
				(enabled no)
				(sheetname "")
			)
			(fill
				(thermal_gap 0.5)
				(thermal_bridge_width 0.5)
				(island_removal_mode 0)
			)
			(polygon
				(pts
					(xy 191.857122 -150.413212) (xy 191.857122 -149.143212) (xy 192.619122 -149.143212) (xy 192.619122 -150.413212)
				)
			)
		)
	)
	(footprint ""
		(layer "F.Cu")
		(at 182.118 -47.8282 -90)
		(property "Reference" "C4E24"
			(at 2.05867 9.652 0)
			(unlocked yes)
			(layer "F.SilkS")
			(effects
				(font
					(size 0.7874 0.5842)
					(thickness 0.1524)
				)
			)
		)
		(property "Value" ""
			(at 0 0 270)
			(layer "F.Fab")
			(effects
				(font
					(size 1.27 1.27)
				)
			)
		)
		(duplicate_pad_numbers_are_jumpers no)
		(fp_line
			(start -2.286 7.366)
			(end -1.60147 7.366)
			(stroke
				(width 0.1524)
				(type default)
			)
			(layer "F.SilkS")
		)
		(fp_line
			(start -2.286 7.366)
			(end -2.286 1.632712)
			(stroke
				(width 0.1524)
				(type default)
			)
			(layer "F.SilkS")
		)
		(fp_line
			(start 2.286 7.366)
			(end 1.600708 7.366)
			(stroke
				(width 0.1524)
				(type default)
			)
			(layer "F.SilkS")
		)
		(fp_line
			(start 2.286 7.366)
			(end 2.286 1.63195)
			(stroke
				(width 0.1524)
				(type default)
			)
			(layer "F.SilkS")
		)
		(fp_line
			(start -2.563114 1.633728)
			(end -1.6002 1.633728)
			(stroke
				(width 0.1524)
				(type default)
			)
			(layer "F.SilkS")
		)
		(fp_line
			(start 2.504948 1.633728)
			(end 1.6002 1.633728)
			(stroke
				(width 0.1524)
				(type default)
			)
			(layer "F.SilkS")
		)
		(fp_line
			(start -2.563114 -1.616456)
			(end -2.563114 1.633728)
			(stroke
				(width 0.1524)
				(type default)
			)
			(layer "F.SilkS")
		)
		(fp_line
			(start -1.6002 -1.616456)
			(end -2.563114 -1.616456)
			(stroke
				(width 0.1524)
				(type default)
			)
			(layer "F.SilkS")
		)
		(fp_line
			(start 1.6002 -1.616456)
			(end 2.504948 -1.616456)
			(stroke
				(width 0.1524)
				(type default)
			)
			(layer "F.SilkS")
		)
		(fp_line
			(start 2.504948 -1.616456)
			(end 2.504948 1.633728)
			(stroke
				(width 0.1524)
				(type default)
			)
			(layer "F.SilkS")
		)
		(fp_rect
			(start -2.286 7.366)
			(end 2.286 -0.254)
			(stroke
				(width 0)
				(type default)
			)
			(fill no)
			(layer "F.CrtYd")
		)
		(fp_line
			(start -2.286 7.366)
			(end -2.286 -0.254)
			(stroke
				(width 0.1)
				(type default)
			)
			(layer "F.Fab")
		)
		(fp_line
			(start 2.286 7.366)
			(end -2.286 7.366)
			(stroke
				(width 0.1)
				(type default)
			)
			(layer "F.Fab")
		)
		(fp_line
			(start -2.286 -0.254)
			(end 2.286 -0.254)
			(stroke
				(width 0.1)
				(type default)
			)
			(layer "F.Fab")
		)
		(fp_line
			(start 2.286 -0.254)
			(end 2.286 7.366)
			(stroke
				(width 0.1)
				(type default)
			)
			(layer "F.Fab")
		)
		(pad "1" smd rect
			(at 0 0 270)
			(size 2.54 3.048)
			(layers "F.Cu" "F.Mask" "F.Paste")
			(net "PVCCMCP_CPU1")
		)
		(pad "2" smd rect
			(at 0 7.112 270)
			(size 2.54 3.048)
			(layers "F.Cu" "F.Mask" "F.Paste")
			(net "GND")
		)
	)
	(footprint ""
		(layer "F.Cu")
		(at 36.425886 -85.6996 -90)
		(property "Reference" "RT10"
			(at 0 0 270)
			(layer "F.SilkS")
			(hide yes)
			(effects
				(font
					(size 1.27 1.27)
				)
			)
		)
		(property "Value" "*"
			(at -0.0254 -2.6289 270)
			(unlocked yes)
			(layer "F.Fab")
			(hide yes)
			(effects
				(font
					(size 1.27 1.016)
					(thickness 0.1524)
				)
			)
		)
		(property "Device Type" "1R3F-GP_RCL_GP-1R3F-GP,64.1R00A"
			(at -0.0254 -4.1529 270)
			(unlocked yes)
			(layer "F.Fab")
			(hide yes)
			(effects
				(font
					(size 1.27 1.016)
					(thickness 0.1524)
				)
			)
		)
		(duplicate_pad_numbers_are_jumpers no)
		(fp_line
			(start -0.4826 0)
			(end -0.2032 0)
			(stroke
				(width 0.2032)
				(type default)
			)
			(layer "F.SilkS")
		)
		(fp_line
			(start 0.2032 0)
			(end 0.4826 0)
			(stroke
				(width 0.2032)
				(type default)
			)
			(layer "F.SilkS")
		)
		(fp_rect
			(start -0.5842 1.3335)
			(end 0.5842 -1.3335)
			(stroke
				(width 0)
				(type default)
			)
			(fill no)
			(layer "F.CrtYd")
		)
		(fp_rect
			(start -0.5842 1.3335)
			(end 0.5842 -1.3335)
			(stroke
				(width 0)
				(type default)
			)
			(fill no)
			(layer "F.Fab")
		)
		(pad "1" smd custom
			(at 0 -0.762 270)
			(size 0.2159 0.2159)
			(layers "F.Cu" "F.Mask" "F.Paste")
			(net "VR_PVCCIN_CPU1_PHASE5_RC")
			(options
				(clearance outline)
				(anchor circle)
			)
			(primitives
				(gr_poly
					(pts
						(arc
							(start -0.3302 -0.4318)
							(mid -0.402042 -0.402042)
							(end -0.4318 -0.3302)
						)
						(arc
							(start -0.4318 0.3302)
							(mid -0.402042 0.402042)
							(end -0.3302 0.4318)
						)
						(arc
							(start 0.3302 0.4318)
							(mid 0.402042 0.402042)
							(end 0.4318 0.3302)
						)
						(arc
							(start 0.4318 -0.3302)
							(mid 0.402042 -0.402042)
							(end 0.3302 -0.4318)
						)
					)
					(width 0)
					(fill yes)
				)
			)
		)
		(pad "2" smd custom
			(at 0 0.762 270)
			(size 0.2159 0.2159)
			(layers "F.Cu" "F.Mask" "F.Paste")
			(net "GND")
			(options
				(clearance outline)
				(anchor circle)
			)
			(primitives
				(gr_poly
					(pts
						(arc
							(start -0.3302 -0.4318)
							(mid -0.402042 -0.402042)
							(end -0.4318 -0.3302)
						)
						(arc
							(start -0.4318 0.3302)
							(mid -0.402042 0.402042)
							(end -0.3302 0.4318)
						)
						(arc
							(start 0.3302 0.4318)
							(mid 0.402042 0.402042)
							(end 0.4318 0.3302)
						)
						(arc
							(start 0.4318 -0.3302)
							(mid 0.402042 -0.402042)
							(end 0.3302 -0.4318)
						)
					)
					(width 0)
					(fill yes)
				)
			)
		)
	)
)
